(kicad_pcb
	(version 20260206)
	(generator "pcbnew")
	(generator_version "10.0")
	(general
		(thickness 1.6)
		(legacy_teardrops no)
	)
	(paper "A4")
	(title_block
		(title "12092022_DA0F0TMDCD0_F0T_Management_Board_D_brd_V3_OCP.brd")
		(comment 1 "Grand Teton / footprints 1141-1146 of 1440")
	)
	(layers
		(0 "F.Cu" signal "TOP")
		(4 "In1.Cu" signal "GND")
		(6 "In2.Cu" signal "IN1")
		(8 "In3.Cu" signal "GND1")
		(10 "In4.Cu" signal "IN2")
		(12 "In5.Cu" signal "VCC")
		(14 "In6.Cu" signal "VCC1")
		(16 "In7.Cu" signal "IN3")
		(18 "In8.Cu" signal "GND2")
		(20 "In9.Cu" signal "IN4")
		(22 "In10.Cu" signal "GND3")
		(2 "B.Cu" signal "BOTTOM")
		(9 "F.Adhes" user "F.Adhesive")
		(11 "B.Adhes" user "B.Adhesive")
		(13 "F.Paste" user "Package Geometry/Pastemask Top")
		(15 "B.Paste" user "Package Geometry/Pastemask Bottom")
		(5 "F.SilkS" user "Ref Des/Silkscreen Top")
		(7 "B.SilkS" user "Ref Des/Silkscreen Bottom")
		(1 "F.Mask" user "Board Geometry/Soldermask Top")
		(3 "B.Mask" user "Board Geometry/Soldermask Bottom")
		(17 "Dwgs.User" user "User.Drawings")
		(19 "Cmts.User" user "User.Comments")
		(21 "Eco1.User" user "User.Eco1")
		(23 "Eco2.User" user "User.Eco2")
		(25 "Edge.Cuts" user "Board Geometry/Outline")
		(27 "Margin" user)
		(31 "F.CrtYd" user "Package Geometry/Place Bound Top")
		(29 "B.CrtYd" user "Package Geometry/Place Bound Bottom")
		(35 "F.Fab" user "Ref Des/Assembly Top")
		(33 "B.Fab" user "Ref Des/Assembly Bottom")
	)
	(footprint ""
		(layer "B.Cu")
		(at 50.546 -34.6456 -90)
		(property "Reference" "R152"
			(at 0 0 90)
			(layer "B.SilkS")
			(hide yes)
			(effects
				(font
					(size 1.27 1.27)
				)
				(justify mirror)
			)
		)
		(property "Value" ""
			(at 0 0 90)
			(layer "B.Fab")
			(effects
				(font
					(size 1.27 1.27)
				)
				(justify mirror)
			)
		)
		(duplicate_pad_numbers_are_jumpers no)
		(fp_line
			(start -0.7874 0.4064)
			(end 0.7874 0.4064)
			(stroke
				(width 0.1524)
				(type default)
			)
			(layer "B.SilkS")
		)
		(fp_line
			(start 0.7874 0.4064)
			(end 0.7874 -0.4064)
			(stroke
				(width 0.1524)
				(type default)
			)
			(layer "B.SilkS")
		)
		(fp_line
			(start -0.7874 -0.4064)
			(end -0.7874 0.4064)
			(stroke
				(width 0.1524)
				(type default)
			)
			(layer "B.SilkS")
		)
		(fp_line
			(start 0.7874 -0.4064)
			(end -0.7874 -0.4064)
			(stroke
				(width 0.1524)
				(type default)
			)
			(layer "B.SilkS")
		)
		(fp_line
			(start -0.67945 0.3048)
			(end -0.120396 0.3048)
			(stroke
				(width 0.1)
				(type default)
			)
			(layer "B.Fab")
		)
		(fp_line
			(start -0.120396 0.3048)
			(end -0.120396 0.2794)
			(stroke
				(width 0.1)
				(type default)
			)
			(layer "B.Fab")
		)
		(fp_line
			(start 0.12065 0.3048)
			(end 0.67945 0.3048)
			(stroke
				(width 0.1)
				(type default)
			)
			(layer "B.Fab")
		)
		(fp_line
			(start 0.67945 0.3048)
			(end 0.67945 -0.305054)
			(stroke
				(width 0.1)
				(type default)
			)
			(layer "B.Fab")
		)
		(fp_line
			(start -0.120396 0.2794)
			(end 0.12065 0.2794)
			(stroke
				(width 0.1)
				(type default)
			)
			(layer "B.Fab")
		)
		(fp_line
			(start 0.12065 0.2794)
			(end 0.12065 0.3048)
			(stroke
				(width 0.1)
				(type default)
			)
			(layer "B.Fab")
		)
		(fp_line
			(start -0.12065 -0.2794)
			(end -0.12065 -0.3048)
			(stroke
				(width 0.1)
				(type default)
			)
			(layer "B.Fab")
		)
		(fp_line
			(start 0.12065 -0.2794)
			(end -0.12065 -0.2794)
			(stroke
				(width 0.1)
				(type default)
			)
			(layer "B.Fab")
		)
		(fp_line
			(start -0.67945 -0.3048)
			(end -0.67945 0.3048)
			(stroke
				(width 0.1)
				(type default)
			)
			(layer "B.Fab")
		)
		(fp_line
			(start -0.12065 -0.3048)
			(end -0.67945 -0.3048)
			(stroke
				(width 0.1)
				(type default)
			)
			(layer "B.Fab")
		)
		(fp_line
			(start 0.12065 -0.305054)
			(end 0.12065 -0.2794)
			(stroke
				(width 0.1)
				(type default)
			)
			(layer "B.Fab")
		)
		(fp_line
			(start 0.67945 -0.305054)
			(end 0.12065 -0.305054)
			(stroke
				(width 0.1)
				(type default)
			)
			(layer "B.Fab")
		)
		(pad "1" smd circle
			(at 0.40005 0 90)
			(size 0 0)
			(layers "B.Cu" "B.Mask" "B.Paste")
			(net "SMB_BMC_MM16_SCL")
		)
		(pad "2" smd circle
			(at -0.40005 0 90)
			(size 0 0)
			(layers "B.Cu" "B.Mask" "B.Paste")
			(net "SMB_BMC_MM16_R_SCL")
		)
	)
	(footprint ""
		(layer "B.Cu")
		(at 31.369 -32.131 90)
		(property "Reference" "C208"
			(at 0 0 90)
			(layer "B.SilkS")
			(hide yes)
			(effects
				(font
					(size 1.27 1.27)
				)
				(justify mirror)
			)
		)
		(property "Value" ""
			(at 0 0 90)
			(layer "B.Fab")
			(effects
				(font
					(size 1.27 1.27)
				)
				(justify mirror)
			)
		)
		(duplicate_pad_numbers_are_jumpers no)
		(fp_line
			(start 0.7874 -0.4064)
			(end -0.7874 -0.4064)
			(stroke
				(width 0.1524)
				(type default)
			)
			(layer "B.SilkS")
		)
		(fp_line
			(start -0.7874 -0.4064)
			(end -0.7874 0.4064)
			(stroke
				(width 0.1524)
				(type default)
			)
			(layer "B.SilkS")
		)
		(fp_line
			(start 0.7874 0.4064)
			(end 0.7874 -0.4064)
			(stroke
				(width 0.1524)
				(type default)
			)
			(layer "B.SilkS")
		)
		(fp_line
			(start -0.7874 0.4064)
			(end 0.7874 0.4064)
			(stroke
				(width 0.1524)
				(type default)
			)
			(layer "B.SilkS")
		)
		(fp_line
			(start 0.67945 -0.305054)
			(end 0.12065 -0.305054)
			(stroke
				(width 0.1)
				(type default)
			)
			(layer "B.Fab")
		)
		(fp_line
			(start 0.12065 -0.305054)
			(end 0.12065 -0.2794)
			(stroke
				(width 0.1)
				(type default)
			)
			(layer "B.Fab")
		)
		(fp_line
			(start -0.12065 -0.3048)
			(end -0.67945 -0.3048)
			(stroke
				(width 0.1)
				(type default)
			)
			(layer "B.Fab")
		)
		(fp_line
			(start -0.67945 -0.3048)
			(end -0.67945 0.3048)
			(stroke
				(width 0.1)
				(type default)
			)
			(layer "B.Fab")
		)
		(fp_line
			(start 0.12065 -0.2794)
			(end -0.12065 -0.2794)
			(stroke
				(width 0.1)
				(type default)
			)
			(layer "B.Fab")
		)
		(fp_line
			(start -0.12065 -0.2794)
			(end -0.12065 -0.3048)
			(stroke
				(width 0.1)
				(type default)
			)
			(layer "B.Fab")
		)
		(fp_line
			(start 0.12065 0.2794)
			(end 0.12065 0.3048)
			(stroke
				(width 0.1)
				(type default)
			)
			(layer "B.Fab")
		)
		(fp_line
			(start -0.120396 0.2794)
			(end 0.12065 0.2794)
			(stroke
				(width 0.1)
				(type default)
			)
			(layer "B.Fab")
		)
		(fp_line
			(start 0.67945 0.3048)
			(end 0.67945 -0.305054)
			(stroke
				(width 0.1)
				(type default)
			)
			(layer "B.Fab")
		)
		(fp_line
			(start 0.12065 0.3048)
			(end 0.67945 0.3048)
			(stroke
				(width 0.1)
				(type default)
			)
			(layer "B.Fab")
		)
		(fp_line
			(start -0.120396 0.3048)
			(end -0.120396 0.2794)
			(stroke
				(width 0.1)
				(type default)
			)
			(layer "B.Fab")
		)
		(fp_line
			(start -0.67945 0.3048)
			(end -0.120396 0.3048)
			(stroke
				(width 0.1)
				(type default)
			)
			(layer "B.Fab")
		)
		(pad "1" smd circle
			(at 0.40005 0 270)
			(size 0 0)
			(layers "B.Cu" "B.Mask" "B.Paste")
			(net "V_DACR_IO")
		)
		(pad "2" smd circle
			(at -0.40005 0 270)
			(size 0 0)
			(layers "B.Cu" "B.Mask" "B.Paste")
			(net "GND")
		)
	)
	(footprint ""
		(layer "B.Cu")
		(at 68.608448 -27.489404 180)
		(property "Reference" "R420"
			(at 0 0 0)
			(layer "B.SilkS")
			(hide yes)
			(effects
				(font
					(size 1.27 1.27)
				)
				(justify mirror)
			)
		)
		(property "Value" ""
			(at 0 0 0)
			(layer "B.Fab")
			(effects
				(font
					(size 1.27 1.27)
				)
				(justify mirror)
			)
		)
		(duplicate_pad_numbers_are_jumpers no)
		(fp_line
			(start 0.7874 0.4064)
			(end 0.7874 -0.4064)
			(stroke
				(width 0.1524)
				(type default)
			)
			(layer "B.SilkS")
		)
		(fp_line
			(start 0.7874 -0.4064)
			(end -0.7874 -0.4064)
			(stroke
				(width 0.1524)
				(type default)
			)
			(layer "B.SilkS")
		)
		(fp_line
			(start -0.7874 0.4064)
			(end 0.7874 0.4064)
			(stroke
				(width 0.1524)
				(type default)
			)
			(layer "B.SilkS")
		)
		(fp_line
			(start -0.7874 -0.4064)
			(end -0.7874 0.4064)
			(stroke
				(width 0.1524)
				(type default)
			)
			(layer "B.SilkS")
		)
		(fp_line
			(start 0.67945 0.3048)
			(end 0.67945 -0.305054)
			(stroke
				(width 0.1)
				(type default)
			)
			(layer "B.Fab")
		)
		(fp_line
			(start 0.67945 -0.305054)
			(end 0.12065 -0.305054)
			(stroke
				(width 0.1)
				(type default)
			)
			(layer "B.Fab")
		)
		(fp_line
			(start 0.12065 0.3048)
			(end 0.67945 0.3048)
			(stroke
				(width 0.1)
				(type default)
			)
			(layer "B.Fab")
		)
		(fp_line
			(start 0.12065 0.2794)
			(end 0.12065 0.3048)
			(stroke
				(width 0.1)
				(type default)
			)
			(layer "B.Fab")
		)
		(fp_line
			(start 0.12065 -0.2794)
			(end -0.12065 -0.2794)
			(stroke
				(width 0.1)
				(type default)
			)
			(layer "B.Fab")
		)
		(fp_line
			(start 0.12065 -0.305054)
			(end 0.12065 -0.2794)
			(stroke
				(width 0.1)
				(type default)
			)
			(layer "B.Fab")
		)
		(fp_line
			(start -0.120396 0.3048)
			(end -0.120396 0.2794)
			(stroke
				(width 0.1)
				(type default)
			)
			(layer "B.Fab")
		)
		(fp_line
			(start -0.120396 0.2794)
			(end 0.12065 0.2794)
			(stroke
				(width 0.1)
				(type default)
			)
			(layer "B.Fab")
		)
		(fp_line
			(start -0.12065 -0.2794)
			(end -0.12065 -0.3048)
			(stroke
				(width 0.1)
				(type default)
			)
			(layer "B.Fab")
		)
		(fp_line
			(start -0.12065 -0.3048)
			(end -0.67945 -0.3048)
			(stroke
				(width 0.1)
				(type default)
			)
			(layer "B.Fab")
		)
		(fp_line
			(start -0.67945 0.3048)
			(end -0.120396 0.3048)
			(stroke
				(width 0.1)
				(type default)
			)
			(layer "B.Fab")
		)
		(fp_line
			(start -0.67945 -0.3048)
			(end -0.67945 0.3048)
			(stroke
				(width 0.1)
				(type default)
			)
			(layer "B.Fab")
		)
		(pad "1" smd circle
			(at 0.40005 0)
			(size 0 0)
			(layers "B.Cu" "B.Mask" "B.Paste")
			(net "SMB_BMC_MM16_R2_SCL")
		)
		(pad "2" smd circle
			(at -0.40005 0)
			(size 0 0)
			(layers "B.Cu" "B.Mask" "B.Paste")
			(net "SMB_BMC_MM16_SCL")
		)
	)
	(footprint ""
		(layer "B.Cu")
		(at 39.75735 -38.532308 -90)
		(property "Reference" "C35"
			(at 0 0 90)
			(layer "B.SilkS")
			(hide yes)
			(effects
				(font
					(size 1.27 1.27)
				)
				(justify mirror)
			)
		)
		(property "Value" ""
			(at 0 0 90)
			(layer "B.Fab")
			(effects
				(font
					(size 1.27 1.27)
				)
				(justify mirror)
			)
		)
		(duplicate_pad_numbers_are_jumpers no)
		(fp_line
			(start -0.7874 0.4064)
			(end 0.7874 0.4064)
			(stroke
				(width 0.1524)
				(type default)
			)
			(layer "B.SilkS")
		)
		(fp_line
			(start 0.7874 0.4064)
			(end 0.7874 -0.4064)
			(stroke
				(width 0.1524)
				(type default)
			)
			(layer "B.SilkS")
		)
		(fp_line
			(start -0.7874 -0.4064)
			(end -0.7874 0.4064)
			(stroke
				(width 0.1524)
				(type default)
			)
			(layer "B.SilkS")
		)
		(fp_line
			(start 0.7874 -0.4064)
			(end -0.7874 -0.4064)
			(stroke
				(width 0.1524)
				(type default)
			)
			(layer "B.SilkS")
		)
		(fp_line
			(start -0.67945 0.3048)
			(end -0.120396 0.3048)
			(stroke
				(width 0.1)
				(type default)
			)
			(layer "B.Fab")
		)
		(fp_line
			(start -0.120396 0.3048)
			(end -0.120396 0.2794)
			(stroke
				(width 0.1)
				(type default)
			)
			(layer "B.Fab")
		)
		(fp_line
			(start 0.12065 0.3048)
			(end 0.67945 0.3048)
			(stroke
				(width 0.1)
				(type default)
			)
			(layer "B.Fab")
		)
		(fp_line
			(start 0.67945 0.3048)
			(end 0.67945 -0.305054)
			(stroke
				(width 0.1)
				(type default)
			)
			(layer "B.Fab")
		)
		(fp_line
			(start -0.120396 0.2794)
			(end 0.12065 0.2794)
			(stroke
				(width 0.1)
				(type default)
			)
			(layer "B.Fab")
		)
		(fp_line
			(start 0.12065 0.2794)
			(end 0.12065 0.3048)
			(stroke
				(width 0.1)
				(type default)
			)
			(layer "B.Fab")
		)
		(fp_line
			(start -0.12065 -0.2794)
			(end -0.12065 -0.3048)
			(stroke
				(width 0.1)
				(type default)
			)
			(layer "B.Fab")
		)
		(fp_line
			(start 0.12065 -0.2794)
			(end -0.12065 -0.2794)
			(stroke
				(width 0.1)
				(type default)
			)
			(layer "B.Fab")
		)
		(fp_line
			(start -0.67945 -0.3048)
			(end -0.67945 0.3048)
			(stroke
				(width 0.1)
				(type default)
			)
			(layer "B.Fab")
		)
		(fp_line
			(start -0.12065 -0.3048)
			(end -0.67945 -0.3048)
			(stroke
				(width 0.1)
				(type default)
			)
			(layer "B.Fab")
		)
		(fp_line
			(start 0.12065 -0.305054)
			(end 0.12065 -0.2794)
			(stroke
				(width 0.1)
				(type default)
			)
			(layer "B.Fab")
		)
		(fp_line
			(start 0.67945 -0.305054)
			(end 0.12065 -0.305054)
			(stroke
				(width 0.1)
				(type default)
			)
			(layer "B.Fab")
		)
		(pad "1" smd circle
			(at 0.40005 0 90)
			(size 0 0)
			(layers "B.Cu" "B.Mask" "B.Paste")
			(net "P3V3_P1V8_SD1VDD")
		)
		(pad "2" smd circle
			(at -0.40005 0 90)
			(size 0 0)
			(layers "B.Cu" "B.Mask" "B.Paste")
			(net "GND")
		)
	)
	(footprint ""
		(layer "B.Cu")
		(at 63.9572 -92.2274 180)
		(property "Reference" "R744"
			(at 0 0 0)
			(layer "B.SilkS")
			(hide yes)
			(effects
				(font
					(size 1.27 1.27)
				)
				(justify mirror)
			)
		)
		(property "Value" ""
			(at 0 0 0)
			(layer "B.Fab")
			(effects
				(font
					(size 1.27 1.27)
				)
				(justify mirror)
			)
		)
		(duplicate_pad_numbers_are_jumpers no)
		(fp_line
			(start 0.7874 0.4064)
			(end 0.7874 -0.4064)
			(stroke
				(width 0.1524)
				(type default)
			)
			(layer "B.SilkS")
		)
		(fp_line
			(start 0.7874 -0.4064)
			(end -0.7874 -0.4064)
			(stroke
				(width 0.1524)
				(type default)
			)
			(layer "B.SilkS")
		)
		(fp_line
			(start -0.7874 0.4064)
			(end 0.7874 0.4064)
			(stroke
				(width 0.1524)
				(type default)
			)
			(layer "B.SilkS")
		)
		(fp_line
			(start -0.7874 -0.4064)
			(end -0.7874 0.4064)
			(stroke
				(width 0.1524)
				(type default)
			)
			(layer "B.SilkS")
		)
		(fp_line
			(start 0.67945 0.3048)
			(end 0.67945 -0.305054)
			(stroke
				(width 0.1)
				(type default)
			)
			(layer "B.Fab")
		)
		(fp_line
			(start 0.67945 -0.305054)
			(end 0.12065 -0.305054)
			(stroke
				(width 0.1)
				(type default)
			)
			(layer "B.Fab")
		)
		(fp_line
			(start 0.12065 0.3048)
			(end 0.67945 0.3048)
			(stroke
				(width 0.1)
				(type default)
			)
			(layer "B.Fab")
		)
		(fp_line
			(start 0.12065 0.2794)
			(end 0.12065 0.3048)
			(stroke
				(width 0.1)
				(type default)
			)
			(layer "B.Fab")
		)
		(fp_line
			(start 0.12065 -0.2794)
			(end -0.12065 -0.2794)
			(stroke
				(width 0.1)
				(type default)
			)
			(layer "B.Fab")
		)
		(fp_line
			(start 0.12065 -0.305054)
			(end 0.12065 -0.2794)
			(stroke
				(width 0.1)
				(type default)
			)
			(layer "B.Fab")
		)
		(fp_line
			(start -0.120396 0.3048)
			(end -0.120396 0.2794)
			(stroke
				(width 0.1)
				(type default)
			)
			(layer "B.Fab")
		)
		(fp_line
			(start -0.120396 0.2794)
			(end 0.12065 0.2794)
			(stroke
				(width 0.1)
				(type default)
			)
			(layer "B.Fab")
		)
		(fp_line
			(start -0.12065 -0.2794)
			(end -0.12065 -0.3048)
			(stroke
				(width 0.1)
				(type default)
			)
			(layer "B.Fab")
		)
		(fp_line
			(start -0.12065 -0.3048)
			(end -0.67945 -0.3048)
			(stroke
				(width 0.1)
				(type default)
			)
			(layer "B.Fab")
		)
		(fp_line
			(start -0.67945 0.3048)
			(end -0.120396 0.3048)
			(stroke
				(width 0.1)
				(type default)
			)
			(layer "B.Fab")
		)
		(fp_line
			(start -0.67945 -0.3048)
			(end -0.67945 0.3048)
			(stroke
				(width 0.1)
				(type default)
			)
			(layer "B.Fab")
		)
		(pad "1" smd circle
			(at 0.40005 0)
			(size 0 0)
			(layers "B.Cu" "B.Mask" "B.Paste")
			(net "LED_POSTCODE_A1")
		)
		(pad "2" smd circle
			(at -0.40005 0)
			(size 0 0)
			(layers "B.Cu" "B.Mask" "B.Paste")
			(net "GND")
		)
	)
	(footprint ""
		(layer "B.Cu")
		(at 44.384214 -30.816804 -90)
		(property "Reference" "R251"
			(at 0 0 90)
			(layer "B.SilkS")
			(hide yes)
			(effects
				(font
					(size 1.27 1.27)
				)
				(justify mirror)
			)
		)
		(property "Value" ""
			(at 0 0 90)
			(layer "B.Fab")
			(effects
				(font
					(size 1.27 1.27)
				)
				(justify mirror)
			)
		)
		(duplicate_pad_numbers_are_jumpers no)
		(fp_line
			(start -0.7874 0.4064)
			(end 0.7874 0.4064)
			(stroke
				(width 0.1524)
				(type default)
			)
			(layer "B.SilkS")
		)
		(fp_line
			(start 0.7874 0.4064)
			(end 0.7874 -0.4064)
			(stroke
				(width 0.1524)
				(type default)
			)
			(layer "B.SilkS")
		)
		(fp_line
			(start -0.7874 -0.4064)
			(end -0.7874 0.4064)
			(stroke
				(width 0.1524)
				(type default)
			)
			(layer "B.SilkS")
		)
		(fp_line
			(start 0.7874 -0.4064)
			(end -0.7874 -0.4064)
			(stroke
				(width 0.1524)
				(type default)
			)
			(layer "B.SilkS")
		)
		(fp_line
			(start -0.67945 0.3048)
			(end -0.120396 0.3048)
			(stroke
				(width 0.1)
				(type default)
			)
			(layer "B.Fab")
		)
		(fp_line
			(start -0.120396 0.3048)
			(end -0.120396 0.2794)
			(stroke
				(width 0.1)
				(type default)
			)
			(layer "B.Fab")
		)
		(fp_line
			(start 0.12065 0.3048)
			(end 0.67945 0.3048)
			(stroke
				(width 0.1)
				(type default)
			)
			(layer "B.Fab")
		)
		(fp_line
			(start 0.67945 0.3048)
			(end 0.67945 -0.305054)
			(stroke
				(width 0.1)
				(type default)
			)
			(layer "B.Fab")
		)
		(fp_line
			(start -0.120396 0.2794)
			(end 0.12065 0.2794)
			(stroke
				(width 0.1)
				(type default)
			)
			(layer "B.Fab")
		)
		(fp_line
			(start 0.12065 0.2794)
			(end 0.12065 0.3048)
			(stroke
				(width 0.1)
				(type default)
			)
			(layer "B.Fab")
		)
		(fp_line
			(start -0.12065 -0.2794)
			(end -0.12065 -0.3048)
			(stroke
				(width 0.1)
				(type default)
			)
			(layer "B.Fab")
		)
		(fp_line
			(start 0.12065 -0.2794)
			(end -0.12065 -0.2794)
			(stroke
				(width 0.1)
				(type default)
			)
			(layer "B.Fab")
		)
		(fp_line
			(start -0.67945 -0.3048)
			(end -0.67945 0.3048)
			(stroke
				(width 0.1)
				(type default)
			)
			(layer "B.Fab")
		)
		(fp_line
			(start -0.12065 -0.3048)
			(end -0.67945 -0.3048)
			(stroke
				(width 0.1)
				(type default)
			)
			(layer "B.Fab")
		)
		(fp_line
			(start 0.12065 -0.305054)
			(end 0.12065 -0.2794)
			(stroke
				(width 0.1)
				(type default)
			)
			(layer "B.Fab")
		)
		(fp_line
			(start 0.67945 -0.305054)
			(end 0.12065 -0.305054)
			(stroke
				(width 0.1)
				(type default)
			)
			(layer "B.Fab")
		)
		(pad "1" smd circle
			(at 0.40005 0 90)
			(size 0 0)
			(layers "B.Cu" "B.Mask" "B.Paste")
			(net "P3V3_AUX")
		)
		(pad "2" smd circle
			(at -0.40005 0 90)
			(size 0 0)
			(layers "B.Cu" "B.Mask" "B.Paste")
			(net "SMB_BMC_MM4_SDA")
		)
	)
)
